# SCM (Grand Teton) — schematic netlist excerpt (pin names and nets, part order shuffled) for the footprints in the layout excerpt that follows; sources: Cadence DE-HDL packaged netlist, KiCad conversion of 12092022_DA0F0TMDCD0_F0T_Management_Board_D_brd_V3_OCP.brd

C77  Q_CAP  0.1UF 25V 10% X7R  pkg 0402  page 16 : A = A_BMC_ADCAV33 ; B = GND
R255  Q_RES  10K 1% CHIP  pkg 0402LF  page 27 : A = P3V3_AUX ; B = SMB_BMC_MM6_SDA

(kicad_pcb
	(version 20260206)
	(generator "pcbnew")
	(generator_version "10.0")
	(general
		(thickness 1.6)
		(legacy_teardrops no)
	)
	(paper "A4")
	(title_block
		(title "12092022_DA0F0TMDCD0_F0T_Management_Board_D_brd_V3_OCP.brd")
		(comment 1 "Grand Teton / footprints 1033-1034 of 1440")
	)
	(layers
		(0 "F.Cu" signal "TOP")
		(4 "In1.Cu" signal "GND")
		(6 "In2.Cu" signal "IN1")
		(8 "In3.Cu" signal "GND1")
		(10 "In4.Cu" signal "IN2")
		(12 "In5.Cu" signal "VCC")
		(14 "In6.Cu" signal "VCC1")
		(16 "In7.Cu" signal "IN3")
		(18 "In8.Cu" signal "GND2")
		(20 "In9.Cu" signal "IN4")
		(22 "In10.Cu" signal "GND3")
		(2 "B.Cu" signal "BOTTOM")
		(9 "F.Adhes" user "F.Adhesive")
		(11 "B.Adhes" user "B.Adhesive")
		(13 "F.Paste" user "Package Geometry/Pastemask Top")
		(15 "B.Paste" user "Package Geometry/Pastemask Bottom")
		(5 "F.SilkS" user "Ref Des/Silkscreen Top")
		(7 "B.SilkS" user "Ref Des/Silkscreen Bottom")
		(1 "F.Mask" user "Board Geometry/Soldermask Top")
		(3 "B.Mask" user "Board Geometry/Soldermask Bottom")
		(17 "Dwgs.User" user "User.Drawings")
		(19 "Cmts.User" user "User.Comments")
		(21 "Eco1.User" user "User.Eco1")
		(23 "Eco2.User" user "User.Eco2")
		(25 "Edge.Cuts" user "Board Geometry/Outline")
		(27 "Margin" user)
		(31 "F.CrtYd" user "Package Geometry/Place Bound Top")
		(29 "B.CrtYd" user "Package Geometry/Place Bound Bottom")
		(35 "F.Fab" user "Ref Des/Assembly Top")
		(33 "B.Fab" user "Ref Des/Assembly Bottom")
	)
	(footprint ""
		(layer "B.Cu")
		(at 48.461422 -55.170832 180)
		(property "Reference" "C77"
			(at 0 0 0)
			(layer "B.SilkS")
			(hide yes)
			(effects
				(font
					(size 1.27 1.27)
				)
				(justify mirror)
			)
		)
		(property "Value" ""
			(at 0 0 0)
			(layer "B.Fab")
			(effects
				(font
					(size 1.27 1.27)
				)
				(justify mirror)
			)
		)
		(duplicate_pad_numbers_are_jumpers no)
		(fp_line
			(start 0.7874 0.4064)
			(end 0.7874 -0.4064)
			(stroke
				(width 0.1524)
				(type default)
			)
			(layer "B.SilkS")
		)
		(fp_line
			(start 0.7874 -0.4064)
			(end -0.7874 -0.4064)
			(stroke
				(width 0.1524)
				(type default)
			)
			(layer "B.SilkS")
		)
		(fp_line
			(start -0.7874 0.4064)
			(end 0.7874 0.4064)
			(stroke
				(width 0.1524)
				(type default)
			)
			(layer "B.SilkS")
		)
		(fp_line
			(start -0.7874 -0.4064)
			(end -0.7874 0.4064)
			(stroke
				(width 0.1524)
				(type default)
			)
			(layer "B.SilkS")
		)
		(fp_line
			(start 0.67945 0.3048)
			(end 0.67945 -0.305054)
			(stroke
				(width 0.1)
				(type default)
			)
			(layer "B.Fab")
		)
		(fp_line
			(start 0.67945 -0.305054)
			(end 0.12065 -0.305054)
			(stroke
				(width 0.1)
				(type default)
			)
			(layer "B.Fab")
		)
		(fp_line
			(start 0.12065 0.3048)
			(end 0.67945 0.3048)
			(stroke
				(width 0.1)
				(type default)
			)
			(layer "B.Fab")
		)
		(fp_line
			(start 0.12065 0.2794)
			(end 0.12065 0.3048)
			(stroke
				(width 0.1)
				(type default)
			)
			(layer "B.Fab")
		)
		(fp_line
			(start 0.12065 -0.2794)
			(end -0.12065 -0.2794)
			(stroke
				(width 0.1)
				(type default)
			)
			(layer "B.Fab")
		)
		(fp_line
			(start 0.12065 -0.305054)
			(end 0.12065 -0.2794)
			(stroke
				(width 0.1)
				(type default)
			)
			(layer "B.Fab")
		)
		(fp_line
			(start -0.120396 0.3048)
			(end -0.120396 0.2794)
			(stroke
				(width 0.1)
				(type default)
			)
			(layer "B.Fab")
		)
		(fp_line
			(start -0.120396 0.2794)
			(end 0.12065 0.2794)
			(stroke
				(width 0.1)
				(type default)
			)
			(layer "B.Fab")
		)
		(fp_line
			(start -0.12065 -0.2794)
			(end -0.12065 -0.3048)
			(stroke
				(width 0.1)
				(type default)
			)
			(layer "B.Fab")
		)
		(fp_line
			(start -0.12065 -0.3048)
			(end -0.67945 -0.3048)
			(stroke
				(width 0.1)
				(type default)
			)
			(layer "B.Fab")
		)
		(fp_line
			(start -0.67945 0.3048)
			(end -0.120396 0.3048)
			(stroke
				(width 0.1)
				(type default)
			)
			(layer "B.Fab")
		)
		(fp_line
			(start -0.67945 -0.3048)
			(end -0.67945 0.3048)
			(stroke
				(width 0.1)
				(type default)
			)
			(layer "B.Fab")
		)
		(pad "1" smd circle
			(at 0.40005 0)
			(size 0 0)
			(layers "B.Cu" "B.Mask" "B.Paste")
			(net "A_BMC_ADCAV33")
		)
		(pad "2" smd circle
			(at -0.40005 0)
			(size 0 0)
			(layers "B.Cu" "B.Mask" "B.Paste")
			(net "GND")
		)
	)
	(footprint ""
		(layer "B.Cu")
		(at 57.75198 -30.867604 -90)
		(property "Reference" "R255"
			(at 0 0 90)
			(layer "B.SilkS")
			(hide yes)
			(effects
				(font
					(size 1.27 1.27)
				)
				(justify mirror)
			)
		)
		(property "Value" ""
			(at 0 0 90)
			(layer "B.Fab")
			(effects
				(font
					(size 1.27 1.27)
				)
				(justify mirror)
			)
		)
		(duplicate_pad_numbers_are_jumpers no)
		(fp_line
			(start -0.7874 0.4064)
			(end 0.7874 0.4064)
			(stroke
				(width 0.1524)
				(type default)
			)
			(layer "B.SilkS")
		)
		(fp_line
			(start 0.7874 0.4064)
			(end 0.7874 -0.4064)
			(stroke
				(width 0.1524)
				(type default)
			)
			(layer "B.SilkS")
		)
		(fp_line
			(start -0.7874 -0.4064)
			(end -0.7874 0.4064)
			(stroke
				(width 0.1524)
				(type default)
			)
			(layer "B.SilkS")
		)
		(fp_line
			(start 0.7874 -0.4064)
			(end -0.7874 -0.4064)
			(stroke
				(width 0.1524)
				(type default)
			)
			(layer "B.SilkS")
		)
		(fp_line
			(start -0.67945 0.3048)
			(end -0.120396 0.3048)
			(stroke
				(width 0.1)
				(type default)
			)
			(layer "B.Fab")
		)
		(fp_line
			(start -0.120396 0.3048)
			(end -0.120396 0.2794)
			(stroke
				(width 0.1)
				(type default)
			)
			(layer "B.Fab")
		)
		(fp_line
			(start 0.12065 0.3048)
			(end 0.67945 0.3048)
			(stroke
				(width 0.1)
				(type default)
			)
			(layer "B.Fab")
		)
		(fp_line
			(start 0.67945 0.3048)
			(end 0.67945 -0.305054)
			(stroke
				(width 0.1)
				(type default)
			)
			(layer "B.Fab")
		)
		(fp_line
			(start -0.120396 0.2794)
			(end 0.12065 0.2794)
			(stroke
				(width 0.1)
				(type default)
			)
			(layer "B.Fab")
		)
		(fp_line
			(start 0.12065 0.2794)
			(end 0.12065 0.3048)
			(stroke
				(width 0.1)
				(type default)
			)
			(layer "B.Fab")
		)
		(fp_line
			(start -0.12065 -0.2794)
			(end -0.12065 -0.3048)
			(stroke
				(width 0.1)
				(type default)
			)
			(layer "B.Fab")
		)
		(fp_line
			(start 0.12065 -0.2794)
			(end -0.12065 -0.2794)
			(stroke
				(width 0.1)
				(type default)
			)
			(layer "B.Fab")
		)
		(fp_line
			(start -0.67945 -0.3048)
			(end -0.67945 0.3048)
			(stroke
				(width 0.1)
				(type default)
			)
			(layer "B.Fab")
		)
		(fp_line
			(start -0.12065 -0.3048)
			(end -0.67945 -0.3048)
			(stroke
				(width 0.1)
				(type default)
			)
			(layer "B.Fab")
		)
		(fp_line
			(start 0.12065 -0.305054)
			(end 0.12065 -0.2794)
			(stroke
				(width 0.1)
				(type default)
			)
			(layer "B.Fab")
		)
		(fp_line
			(start 0.67945 -0.305054)
			(end 0.12065 -0.305054)
			(stroke
				(width 0.1)
				(type default)
			)
			(layer "B.Fab")
		)
		(pad "1" smd circle
			(at 0.40005 0 90)
			(size 0 0)
			(layers "B.Cu" "B.Mask" "B.Paste")
			(net "P3V3_AUX")
		)
		(pad "2" smd circle
			(at -0.40005 0 90)
			(size 0 0)
			(layers "B.Cu" "B.Mask" "B.Paste")
			(net "SMB_BMC_MM6_SDA")
		)
	)
)
